# TIMECARD (Time Appliance Project (Time Card)) — schematic netlist excerpt (pin names and nets, part order shuffled) for the footprints in the layout excerpt that follows; sources: Cadence DE-HDL packaged netlist, KiCad conversion of R4006-B0001-02_R01.brd

R472  RESISTOR  0OHM -  pkg SMC_0402R_H016  page 24 : \1\ = R_FT4232_I2C_SDA_OUT ; \2\ = FT4232_I2C_SDA
R499  RESISTOR  1MOHM 1%  pkg SMC_0402R_H016  page 23 : \1\ = SG ; \2\ = BF_SMA2_SIG_IO_CONN

(kicad_pcb
	(version 20260206)
	(generator "pcbnew")
	(generator_version "10.0")
	(general
		(thickness 1.6)
		(legacy_teardrops no)
	)
	(paper "A4")
	(title_block
		(title "timecard-production-celestica-r4006 — R4006-B0001-02_R01.brd")
		(comment 1 "Time Appliance Project (Time Card) / footprints 276-277 of 1113")
	)
	(layers
		(0 "F.Cu" signal "TOP")
		(4 "In1.Cu" signal "L02_GND1")
		(6 "In2.Cu" signal "L03_SIG1")
		(8 "In3.Cu" signal "L04_GND2")
		(10 "In4.Cu" signal "L05_VCC1")
		(12 "In5.Cu" signal "L06_VCC2")
		(14 "In6.Cu" signal "L07_GND3")
		(16 "In7.Cu" signal "L08_SIG2")
		(18 "In8.Cu" signal "L09_GND4")
		(2 "B.Cu" signal "BOTTOM")
		(9 "F.Adhes" user "F.Adhesive")
		(11 "B.Adhes" user "B.Adhesive")
		(13 "F.Paste" user "Package Geometry/Pastemask Top")
		(15 "B.Paste" user "Package Geometry/Pastemask Bottom")
		(5 "F.SilkS" user "Ref Des/Silkscreen Top")
		(7 "B.SilkS" user "Ref Des/Silkscreen Bottom")
		(1 "F.Mask" user "Board Geometry/Soldermask Top")
		(3 "B.Mask" user "Board Geometry/Soldermask Bottom")
		(17 "Dwgs.User" user "User.Drawings")
		(19 "Cmts.User" user "User.Comments")
		(21 "Eco1.User" user "User.Eco1")
		(23 "Eco2.User" user "User.Eco2")
		(25 "Edge.Cuts" user "Board Geometry/Outline")
		(27 "Margin" user)
		(31 "F.CrtYd" user "Package Geometry/Place Bound Top")
		(29 "B.CrtYd" user "Package Geometry/Place Bound Bottom")
		(35 "F.Fab" user "Ref Des/Assembly Top")
		(33 "B.Fab" user "Ref Des/Assembly Bottom")
	)
	(footprint ""
		(layer "F.Cu")
		(at 11.557 -42.291 90)
		(property "Reference" "R499"
			(at 0 -1.16205 90)
			(unlocked yes)
			(layer "F.SilkS")
			(effects
				(font
					(size 0.635 0.4064)
					(thickness 0.1524)
				)
			)
		)
		(property "Value" "VAL*"
			(at 0.02032 2.13233 90)
			(unlocked yes)
			(layer "F.Fab")
			(hide yes)
			(effects
				(font
					(size 0.7874 0.5842)
					(thickness 0.1524)
				)
			)
		)
		(property "Tolerance" "TOL*"
			(at 0.044704 3.05435 90)
			(unlocked yes)
			(layer "Cmts.User")
			(hide yes)
			(effects
				(font
					(size 0.7874 0.5842)
					(thickness 0.1524)
				)
			)
		)
		(property "User Part Number" "PARTNUM*"
			(at 0.02032 4.024884 90)
			(unlocked yes)
			(layer "Cmts.User")
			(hide yes)
			(effects
				(font
					(size 0.7874 0.5842)
					(thickness 0.1524)
				)
			)
		)
		(property "Device Type" "RESISTOR-G155-11004-01,1MOHM,1%"
			(at 0.008382 1.210564 90)
			(unlocked yes)
			(layer "F.Fab")
			(hide yes)
			(effects
				(font
					(size 0.7874 0.5842)
					(thickness 0.1524)
				)
			)
		)
		(duplicate_pad_numbers_are_jumpers no)
		(fp_line
			(start 1.143 -0.5588)
			(end -1.143 -0.5588)
			(stroke
				(width 0.1)
				(type default)
			)
			(layer "F.SilkS")
		)
		(fp_line
			(start -1.143 -0.5588)
			(end -1.143 0.5588)
			(stroke
				(width 0.1)
				(type default)
			)
			(layer "F.SilkS")
		)
		(fp_line
			(start 1.143 0.5588)
			(end 1.143 -0.5588)
			(stroke
				(width 0.1)
				(type default)
			)
			(layer "F.SilkS")
		)
		(fp_line
			(start -1.143 0.5588)
			(end 1.143 0.5588)
			(stroke
				(width 0.1)
				(type default)
			)
			(layer "F.SilkS")
		)
		(fp_poly
			(pts
				(xy -1.143 0.5588) (xy 1.143 0.5588) (xy 1.143 -0.5588) (xy -1.143 -0.5588)
			)
			(stroke
				(width 0)
				(type default)
			)
			(fill no)
			(layer "F.CrtYd")
		)
		(fp_line
			(start 0.508 -0.3048)
			(end -0.508 -0.3048)
			(stroke
				(width 0.1)
				(type default)
			)
			(layer "F.Fab")
		)
		(fp_line
			(start -0.508 -0.3048)
			(end -0.508 0.3048)
			(stroke
				(width 0.1)
				(type default)
			)
			(layer "F.Fab")
		)
		(fp_line
			(start 0.508 0.3048)
			(end 0.508 -0.3048)
			(stroke
				(width 0.1)
				(type default)
			)
			(layer "F.Fab")
		)
		(fp_line
			(start -0.508 0.3048)
			(end 0.508 0.3048)
			(stroke
				(width 0.1)
				(type default)
			)
			(layer "F.Fab")
		)
		(pad "1" smd rect
			(at -0.5334 0 90)
			(size 0.7112 0.6096)
			(layers "F.Cu" "F.Mask" "F.Paste")
			(net "SG")
		)
		(pad "2" smd rect
			(at 0.5334 0 90)
			(size 0.7112 0.6096)
			(layers "F.Cu" "F.Mask" "F.Paste")
			(net "BF_SMA2_SIG_IO_CONN")
		)
		(zone
			(layer "F.Cu")
			(hatch none 0.5)
			(connect_pads
				(clearance 0)
			)
			(min_thickness 0.25)
			(keepout
				(tracks allowed)
				(vias not_allowed)
				(pads allowed)
				(copperpour not_allowed)
				(footprints allowed)
			)
			(placement
				(enabled no)
				(sheetname "")
			)
			(fill
				(thermal_gap 0.5)
				(thermal_bridge_width 0.5)
				(island_removal_mode 0)
			)
			(polygon
				(pts
					(xy 11.8618 -42.2148) (xy 11.8618 -42.3672) (xy 11.2522 -42.3672) (xy 11.2522 -42.2148)
				)
			)
		)
		(zone
			(layer "F.Cu")
			(hatch none 0.5)
			(connect_pads
				(clearance 0)
			)
			(min_thickness 0.25)
			(keepout
				(tracks not_allowed)
				(vias allowed)
				(pads allowed)
				(copperpour not_allowed)
				(footprints allowed)
			)
			(placement
				(enabled no)
				(sheetname "")
			)
			(fill
				(thermal_gap 0.5)
				(thermal_bridge_width 0.5)
				(island_removal_mode 0)
			)
			(polygon
				(pts
					(xy 11.8618 -42.2148) (xy 11.8618 -42.3672) (xy 11.2522 -42.3672) (xy 11.2522 -42.2148)
				)
			)
		)
	)
	(footprint ""
		(layer "F.Cu")
		(at 18.415 -81.28 180)
		(property "Reference" "R472"
			(at 0.635 -2.32537 0)
			(unlocked yes)
			(layer "F.SilkS")
			(effects
				(font
					(size 0.7874 0.5842)
					(thickness 0.1524)
				)
			)
		)
		(property "Value" "VAL*"
			(at 0.02032 2.13233 180)
			(unlocked yes)
			(layer "F.Fab")
			(hide yes)
			(effects
				(font
					(size 0.7874 0.5842)
					(thickness 0.1524)
				)
			)
		)
		(property "Tolerance" "TOL*"
			(at 0.044704 3.05435 180)
			(unlocked yes)
			(layer "Cmts.User")
			(hide yes)
			(effects
				(font
					(size 0.7874 0.5842)
					(thickness 0.1524)
				)
			)
		)
		(property "User Part Number" "PARTNUM*"
			(at 0.02032 4.024884 180)
			(unlocked yes)
			(layer "Cmts.User")
			(hide yes)
			(effects
				(font
					(size 0.7874 0.5842)
					(thickness 0.1524)
				)
			)
		)
		(property "Device Type" "RESISTOR-G155-100R0-J0,0OHM,-"
			(at 0.008382 1.210564 180)
			(unlocked yes)
			(layer "F.Fab")
			(hide yes)
			(effects
				(font
					(size 0.7874 0.5842)
					(thickness 0.1524)
				)
			)
		)
		(duplicate_pad_numbers_are_jumpers no)
		(fp_line
			(start 1.143 0.5588)
			(end 1.143 -0.5588)
			(stroke
				(width 0.1)
				(type default)
			)
			(layer "F.SilkS")
		)
		(fp_line
			(start 1.143 -0.5588)
			(end -1.143 -0.5588)
			(stroke
				(width 0.1)
				(type default)
			)
			(layer "F.SilkS")
		)
		(fp_line
			(start -1.143 0.5588)
			(end 1.143 0.5588)
			(stroke
				(width 0.1)
				(type default)
			)
			(layer "F.SilkS")
		)
		(fp_line
			(start -1.143 -0.5588)
			(end -1.143 0.5588)
			(stroke
				(width 0.1)
				(type default)
			)
			(layer "F.SilkS")
		)
		(fp_poly
			(pts
				(xy -1.143 0.5588) (xy 1.143 0.5588) (xy 1.143 -0.5588) (xy -1.143 -0.5588)
			)
			(stroke
				(width 0)
				(type default)
			)
			(fill no)
			(layer "F.CrtYd")
		)
		(fp_line
			(start 0.508 0.3048)
			(end 0.508 -0.3048)
			(stroke
				(width 0.1)
				(type default)
			)
			(layer "F.Fab")
		)
		(fp_line
			(start 0.508 -0.3048)
			(end -0.508 -0.3048)
			(stroke
				(width 0.1)
				(type default)
			)
			(layer "F.Fab")
		)
		(fp_line
			(start -0.508 0.3048)
			(end 0.508 0.3048)
			(stroke
				(width 0.1)
				(type default)
			)
			(layer "F.Fab")
		)
		(fp_line
			(start -0.508 -0.3048)
			(end -0.508 0.3048)
			(stroke
				(width 0.1)
				(type default)
			)
			(layer "F.Fab")
		)
		(pad "1" smd rect
			(at -0.5334 0 180)
			(size 0.7112 0.6096)
			(layers "F.Cu" "F.Mask" "F.Paste")
			(net "R_FT4232_I2C_SDA_OUT")
		)
		(pad "2" smd rect
			(at 0.5334 0 180)
			(size 0.7112 0.6096)
			(layers "F.Cu" "F.Mask" "F.Paste")
			(net "FT4232_I2C_SDA")
		)
		(zone
			(layer "F.Cu")
			(hatch none 0.5)
			(connect_pads
				(clearance 0)
			)
			(min_thickness 0.25)
			(keepout
				(tracks not_allowed)
				(vias allowed)
				(pads allowed)
				(copperpour not_allowed)
				(footprints allowed)
			)
			(placement
				(enabled no)
				(sheetname "")
			)
			(fill
				(thermal_gap 0.5)
				(thermal_bridge_width 0.5)
				(island_removal_mode 0)
			)
			(polygon
				(pts
					(xy 18.4912 -81.5848) (xy 18.3388 -81.5848) (xy 18.3388 -80.9752) (xy 18.4912 -80.9752)
				)
			)
		)
		(zone
			(layer "F.Cu")
			(hatch none 0.5)
			(connect_pads
				(clearance 0)
			)
			(min_thickness 0.25)
			(keepout
				(tracks allowed)
				(vias not_allowed)
				(pads allowed)
				(copperpour not_allowed)
				(footprints allowed)
			)
			(placement
				(enabled no)
				(sheetname "")
			)
			(fill
				(thermal_gap 0.5)
				(thermal_bridge_width 0.5)
				(island_removal_mode 0)
			)
			(polygon
				(pts
					(xy 18.4912 -81.5848) (xy 18.3388 -81.5848) (xy 18.3388 -80.9752) (xy 18.4912 -80.9752)
				)
			)
		)
	)
)
